(kicad_pcb
	(version 20260206)
	(generator "pcbnew")
	(generator_version "10.0")
	(general
		(thickness 1.6)
		(legacy_teardrops no)
	)
	(paper "A4")
	(title_block
		(title "01162023_DA0F0TEBIF0_F0T_Expander_BD_F_brd_V02_OCP.brd")
		(comment 1 "Grand Teton / footprints 5192-5198 of 9728")
	)
	(layers
		(0 "F.Cu" signal "TOP")
		(4 "In1.Cu" signal "GND")
		(6 "In2.Cu" signal "VCC")
		(8 "In3.Cu" signal "VCC1")
		(10 "In4.Cu" signal "GND1")
		(12 "In5.Cu" signal "IN1")
		(14 "In6.Cu" signal "GND2")
		(16 "In7.Cu" signal "IN2")
		(18 "In8.Cu" signal "GND3")
		(20 "In9.Cu" signal "IN3")
		(22 "In10.Cu" signal "GND4")
		(24 "In11.Cu" signal "IN4")
		(26 "In12.Cu" signal "GND5")
		(28 "In13.Cu" signal "IN5")
		(30 "In14.Cu" signal "GND6")
		(32 "In15.Cu" signal "IN6")
		(34 "In16.Cu" signal "GND7")
		(2 "B.Cu" signal "BOTTOM")
		(9 "F.Adhes" user "F.Adhesive")
		(11 "B.Adhes" user "B.Adhesive")
		(13 "F.Paste" user "Package Geometry/Pastemask Top")
		(15 "B.Paste" user "Package Geometry/Pastemask Bottom")
		(5 "F.SilkS" user "Ref Des/Silkscreen Top")
		(7 "B.SilkS" user "Ref Des/Silkscreen Bottom")
		(1 "F.Mask" user "Board Geometry/Soldermask Top")
		(3 "B.Mask" user "Board Geometry/Soldermask Bottom")
		(17 "Dwgs.User" user "User.Drawings")
		(19 "Cmts.User" user "User.Comments")
		(21 "Eco1.User" user "User.Eco1")
		(23 "Eco2.User" user "User.Eco2")
		(25 "Edge.Cuts" user "Board Geometry/Outline")
		(27 "Margin" user)
		(31 "F.CrtYd" user "Package Geometry/Place Bound Top")
		(29 "B.CrtYd" user "Package Geometry/Place Bound Bottom")
		(35 "F.Fab" user "Ref Des/Assembly Top")
		(33 "B.Fab" user "Ref Des/Assembly Bottom")
	)
	(footprint ""
		(layer "F.Cu")
		(at 263.55294 -335.115408)
		(property "Reference" "U448"
			(at -2.956306 2.612898 0)
			(unlocked yes)
			(layer "F.SilkS")
			(effects
				(font
					(size 0.7874 0.5842)
					(thickness 0.1524)
				)
			)
		)
		(property "Value" ""
			(at 0 0 0)
			(layer "F.Fab")
			(effects
				(font
					(size 1.27 1.27)
				)
			)
		)
		(duplicate_pad_numbers_are_jumpers no)
		(fp_line
			(start -2.032 -1.549908)
			(end -0.508 -1.549908)
			(stroke
				(width 0.1524)
				(type default)
			)
			(layer "F.SilkS")
		)
		(fp_line
			(start -2.032 1.549908)
			(end -2.032 -1.549908)
			(stroke
				(width 0.1524)
				(type default)
			)
			(layer "F.SilkS")
		)
		(fp_line
			(start -0.508 -1.549908)
			(end 0 -0.762)
			(stroke
				(width 0.1524)
				(type default)
			)
			(layer "F.SilkS")
		)
		(fp_line
			(start 0 -0.762)
			(end 0.508 -1.549908)
			(stroke
				(width 0.1524)
				(type default)
			)
			(layer "F.SilkS")
		)
		(fp_line
			(start 0.508 -1.549908)
			(end 2.032 -1.549908)
			(stroke
				(width 0.1524)
				(type default)
			)
			(layer "F.SilkS")
		)
		(fp_line
			(start 2.032 -1.549908)
			(end 2.032 1.549908)
			(stroke
				(width 0.1524)
				(type default)
			)
			(layer "F.SilkS")
		)
		(fp_line
			(start 2.032 1.549908)
			(end -2.032 1.549908)
			(stroke
				(width 0.1524)
				(type default)
			)
			(layer "F.SilkS")
		)
		(fp_poly
			(pts
				(xy -3.2004 -1.45796) (xy -3.2004 -0.44196) (xy -2.1844 -0.94996)
			)
			(stroke
				(width 0)
				(type default)
			)
			(fill yes)
			(layer "F.SilkS")
		)
		(fp_line
			(start -0.849884 -1.549908)
			(end 0.849884 -1.549908)
			(stroke
				(width 0.1)
				(type default)
			)
			(layer "F.Fab")
		)
		(fp_line
			(start -0.849884 1.549908)
			(end -0.849884 -1.549908)
			(stroke
				(width 0.1)
				(type default)
			)
			(layer "F.Fab")
		)
		(fp_line
			(start 0.849884 -1.549908)
			(end 0.849884 1.549908)
			(stroke
				(width 0.1)
				(type default)
			)
			(layer "F.Fab")
		)
		(fp_line
			(start 0.849884 1.549908)
			(end -0.849884 1.549908)
			(stroke
				(width 0.1)
				(type default)
			)
			(layer "F.Fab")
		)
		(fp_poly
			(pts
				(xy -3.2004 -1.45796) (xy -3.2004 -0.44196) (xy -2.1844 -0.94996)
			)
			(stroke
				(width 0)
				(type default)
			)
			(fill yes)
			(layer "F.Fab")
		)
		(pad "1" smd rect
			(at -1.35001 -0.94996 270)
			(size 0.6096 1.0668)
			(layers "F.Cu" "F.Mask" "F.Paste")
			(net "OC_P2V5_COMP")
		)
		(pad "2" smd rect
			(at -1.35001 0 270)
			(size 0.6096 1.0668)
			(layers "F.Cu" "F.Mask" "F.Paste")
			(net "GND")
		)
		(pad "3" smd rect
			(at -1.35001 0.94996 270)
			(size 0.6096 1.0668)
			(layers "F.Cu" "F.Mask" "F.Paste")
			(net "HSC_OC_VOL")
		)
		(pad "4" smd rect
			(at 1.35001 0.94996 270)
			(size 0.6096 1.0668)
			(layers "F.Cu" "F.Mask" "F.Paste")
			(net "HSC_D_OC_R2")
		)
		(pad "5" smd rect
			(at 1.35001 -0.94996 270)
			(size 0.6096 1.0668)
			(layers "F.Cu" "F.Mask" "F.Paste")
			(net "P12V_AUX")
		)
	)
	(footprint ""
		(layer "F.Cu")
		(at 259.24129 -77.279754 -90)
		(property "Reference" "R1080"
			(at 0 0 270)
			(layer "F.SilkS")
			(hide yes)
			(effects
				(font
					(size 1.27 1.27)
				)
			)
		)
		(property "Value" ""
			(at 0 0 270)
			(layer "F.Fab")
			(effects
				(font
					(size 1.27 1.27)
				)
			)
		)
		(duplicate_pad_numbers_are_jumpers no)
		(fp_line
			(start -0.7874 0.4064)
			(end -0.7874 -0.4064)
			(stroke
				(width 0.1524)
				(type default)
			)
			(layer "F.SilkS")
		)
		(fp_line
			(start 0.7874 0.4064)
			(end -0.7874 0.4064)
			(stroke
				(width 0.1524)
				(type default)
			)
			(layer "F.SilkS")
		)
		(fp_line
			(start -0.7874 -0.4064)
			(end 0.7874 -0.4064)
			(stroke
				(width 0.1524)
				(type default)
			)
			(layer "F.SilkS")
		)
		(fp_line
			(start 0.7874 -0.4064)
			(end 0.7874 0.4064)
			(stroke
				(width 0.1524)
				(type default)
			)
			(layer "F.SilkS")
		)
		(fp_line
			(start -0.67945 0.3048)
			(end -0.67945 -0.305054)
			(stroke
				(width 0.1)
				(type default)
			)
			(layer "F.Fab")
		)
		(fp_line
			(start -0.12065 0.3048)
			(end -0.67945 0.3048)
			(stroke
				(width 0.1)
				(type default)
			)
			(layer "F.Fab")
		)
		(fp_line
			(start 0.120396 0.3048)
			(end 0.120396 0.2794)
			(stroke
				(width 0.1)
				(type default)
			)
			(layer "F.Fab")
		)
		(fp_line
			(start 0.67945 0.3048)
			(end 0.120396 0.3048)
			(stroke
				(width 0.1)
				(type default)
			)
			(layer "F.Fab")
		)
		(fp_line
			(start -0.12065 0.2794)
			(end -0.12065 0.3048)
			(stroke
				(width 0.1)
				(type default)
			)
			(layer "F.Fab")
		)
		(fp_line
			(start 0.120396 0.2794)
			(end -0.12065 0.2794)
			(stroke
				(width 0.1)
				(type default)
			)
			(layer "F.Fab")
		)
		(fp_line
			(start -0.12065 -0.2794)
			(end 0.12065 -0.2794)
			(stroke
				(width 0.1)
				(type default)
			)
			(layer "F.Fab")
		)
		(fp_line
			(start 0.12065 -0.2794)
			(end 0.12065 -0.3048)
			(stroke
				(width 0.1)
				(type default)
			)
			(layer "F.Fab")
		)
		(fp_line
			(start 0.12065 -0.3048)
			(end 0.67945 -0.3048)
			(stroke
				(width 0.1)
				(type default)
			)
			(layer "F.Fab")
		)
		(fp_line
			(start 0.67945 -0.3048)
			(end 0.67945 0.3048)
			(stroke
				(width 0.1)
				(type default)
			)
			(layer "F.Fab")
		)
		(fp_line
			(start -0.67945 -0.305054)
			(end -0.12065 -0.305054)
			(stroke
				(width 0.1)
				(type default)
			)
			(layer "F.Fab")
		)
		(fp_line
			(start -0.12065 -0.305054)
			(end -0.12065 -0.2794)
			(stroke
				(width 0.1)
				(type default)
			)
			(layer "F.Fab")
		)
		(pad "1" smd circle
			(at -0.40005 0 270)
			(size 0 0)
			(layers "F.Cu" "F.Mask" "F.Paste")
			(net "CLK_GEN_CK440_OE5_N")
		)
		(pad "2" smd circle
			(at 0.40005 0 270)
			(size 0 0)
			(layers "F.Cu" "F.Mask" "F.Paste")
			(net "P3V3")
		)
	)
	(footprint ""
		(layer "F.Cu")
		(at 271.480534 -111.003334)
		(property "Reference" "C474"
			(at 0 0 0)
			(layer "F.SilkS")
			(hide yes)
			(effects
				(font
					(size 1.27 1.27)
				)
			)
		)
		(property "Value" ""
			(at 0 0 0)
			(layer "F.Fab")
			(effects
				(font
					(size 1.27 1.27)
				)
			)
		)
		(duplicate_pad_numbers_are_jumpers no)
		(fp_line
			(start -0.299974 -0.150114)
			(end 0.299974 -0.150114)
			(stroke
				(width 0.1)
				(type default)
			)
			(layer "F.Fab")
		)
		(fp_line
			(start -0.299974 0.150114)
			(end -0.299974 -0.150114)
			(stroke
				(width 0.1)
				(type default)
			)
			(layer "F.Fab")
		)
		(fp_line
			(start 0.299974 -0.150114)
			(end 0.299974 0.150114)
			(stroke
				(width 0.1)
				(type default)
			)
			(layer "F.Fab")
		)
		(fp_line
			(start 0.299974 0.150114)
			(end -0.299974 0.150114)
			(stroke
				(width 0.1)
				(type default)
			)
			(layer "F.Fab")
		)
		(pad "1" smd rect
			(at -0.2667 0)
			(size 0.3048 0.381)
			(layers "F.Cu" "F.Mask" "F.Paste")
			(net "P5E_PEX2_STN1_TX_DN<22>")
		)
		(pad "2" smd rect
			(at 0.2667 0)
			(size 0.3048 0.381)
			(layers "F.Cu" "F.Mask" "F.Paste")
			(net "P5E_PEX2_STN1_TX_C_DN<22>")
		)
	)
	(footprint ""
		(layer "F.Cu")
		(at 235.623608 -143.656812 180)
		(property "Reference" "R4205"
			(at 0 0 180)
			(layer "F.SilkS")
			(hide yes)
			(effects
				(font
					(size 1.27 1.27)
				)
			)
		)
		(property "Value" ""
			(at 0 0 180)
			(layer "F.Fab")
			(effects
				(font
					(size 1.27 1.27)
				)
			)
		)
		(duplicate_pad_numbers_are_jumpers no)
		(fp_line
			(start 0.7874 0.4064)
			(end -0.7874 0.4064)
			(stroke
				(width 0.1524)
				(type default)
			)
			(layer "F.SilkS")
		)
		(fp_line
			(start 0.7874 -0.4064)
			(end 0.7874 0.4064)
			(stroke
				(width 0.1524)
				(type default)
			)
			(layer "F.SilkS")
		)
		(fp_line
			(start -0.7874 0.4064)
			(end -0.7874 -0.4064)
			(stroke
				(width 0.1524)
				(type default)
			)
			(layer "F.SilkS")
		)
		(fp_line
			(start -0.7874 -0.4064)
			(end 0.7874 -0.4064)
			(stroke
				(width 0.1524)
				(type default)
			)
			(layer "F.SilkS")
		)
		(fp_line
			(start 0.67945 0.3048)
			(end 0.120396 0.3048)
			(stroke
				(width 0.1)
				(type default)
			)
			(layer "F.Fab")
		)
		(fp_line
			(start 0.67945 -0.3048)
			(end 0.67945 0.3048)
			(stroke
				(width 0.1)
				(type default)
			)
			(layer "F.Fab")
		)
		(fp_line
			(start 0.12065 -0.2794)
			(end 0.12065 -0.3048)
			(stroke
				(width 0.1)
				(type default)
			)
			(layer "F.Fab")
		)
		(fp_line
			(start 0.12065 -0.3048)
			(end 0.67945 -0.3048)
			(stroke
				(width 0.1)
				(type default)
			)
			(layer "F.Fab")
		)
		(fp_line
			(start 0.120396 0.3048)
			(end 0.120396 0.2794)
			(stroke
				(width 0.1)
				(type default)
			)
			(layer "F.Fab")
		)
		(fp_line
			(start 0.120396 0.2794)
			(end -0.12065 0.2794)
			(stroke
				(width 0.1)
				(type default)
			)
			(layer "F.Fab")
		)
		(fp_line
			(start -0.12065 0.3048)
			(end -0.67945 0.3048)
			(stroke
				(width 0.1)
				(type default)
			)
			(layer "F.Fab")
		)
		(fp_line
			(start -0.12065 0.2794)
			(end -0.12065 0.3048)
			(stroke
				(width 0.1)
				(type default)
			)
			(layer "F.Fab")
		)
		(fp_line
			(start -0.12065 -0.2794)
			(end 0.12065 -0.2794)
			(stroke
				(width 0.1)
				(type default)
			)
			(layer "F.Fab")
		)
		(fp_line
			(start -0.12065 -0.305054)
			(end -0.12065 -0.2794)
			(stroke
				(width 0.1)
				(type default)
			)
			(layer "F.Fab")
		)
		(fp_line
			(start -0.67945 0.3048)
			(end -0.67945 -0.305054)
			(stroke
				(width 0.1)
				(type default)
			)
			(layer "F.Fab")
		)
		(fp_line
			(start -0.67945 -0.305054)
			(end -0.12065 -0.305054)
			(stroke
				(width 0.1)
				(type default)
			)
			(layer "F.Fab")
		)
		(pad "1" smd circle
			(at -0.40005 0 180)
			(size 0 0)
			(layers "F.Cu" "F.Mask" "F.Paste")
			(net "GND")
		)
		(pad "2" smd circle
			(at 0.40005 0 180)
			(size 0 0)
			(layers "F.Cu" "F.Mask" "F.Paste")
			(net "FM_CLK_EN_R")
		)
	)
	(footprint ""
		(layer "F.Cu")
		(at 206.710534 -187.165234 90)
		(property "Reference" "R3761"
			(at 0 0 90)
			(layer "F.SilkS")
			(hide yes)
			(effects
				(font
					(size 1.27 1.27)
				)
			)
		)
		(property "Value" ""
			(at 0 0 90)
			(layer "F.Fab")
			(effects
				(font
					(size 1.27 1.27)
				)
			)
		)
		(duplicate_pad_numbers_are_jumpers no)
		(fp_line
			(start 0.7874 -0.4064)
			(end 0.7874 0.4064)
			(stroke
				(width 0.1524)
				(type default)
			)
			(layer "F.SilkS")
		)
		(fp_line
			(start -0.7874 -0.4064)
			(end 0.7874 -0.4064)
			(stroke
				(width 0.1524)
				(type default)
			)
			(layer "F.SilkS")
		)
		(fp_line
			(start 0.7874 0.4064)
			(end -0.7874 0.4064)
			(stroke
				(width 0.1524)
				(type default)
			)
			(layer "F.SilkS")
		)
		(fp_line
			(start -0.7874 0.4064)
			(end -0.7874 -0.4064)
			(stroke
				(width 0.1524)
				(type default)
			)
			(layer "F.SilkS")
		)
		(fp_line
			(start -0.12065 -0.305054)
			(end -0.12065 -0.2794)
			(stroke
				(width 0.1)
				(type default)
			)
			(layer "F.Fab")
		)
		(fp_line
			(start -0.67945 -0.305054)
			(end -0.12065 -0.305054)
			(stroke
				(width 0.1)
				(type default)
			)
			(layer "F.Fab")
		)
		(fp_line
			(start 0.67945 -0.3048)
			(end 0.67945 0.3048)
			(stroke
				(width 0.1)
				(type default)
			)
			(layer "F.Fab")
		)
		(fp_line
			(start 0.12065 -0.3048)
			(end 0.67945 -0.3048)
			(stroke
				(width 0.1)
				(type default)
			)
			(layer "F.Fab")
		)
		(fp_line
			(start 0.12065 -0.2794)
			(end 0.12065 -0.3048)
			(stroke
				(width 0.1)
				(type default)
			)
			(layer "F.Fab")
		)
		(fp_line
			(start -0.12065 -0.2794)
			(end 0.12065 -0.2794)
			(stroke
				(width 0.1)
				(type default)
			)
			(layer "F.Fab")
		)
		(fp_line
			(start 0.120396 0.2794)
			(end -0.12065 0.2794)
			(stroke
				(width 0.1)
				(type default)
			)
			(layer "F.Fab")
		)
		(fp_line
			(start -0.12065 0.2794)
			(end -0.12065 0.3048)
			(stroke
				(width 0.1)
				(type default)
			)
			(layer "F.Fab")
		)
		(fp_line
			(start 0.67945 0.3048)
			(end 0.120396 0.3048)
			(stroke
				(width 0.1)
				(type default)
			)
			(layer "F.Fab")
		)
		(fp_line
			(start 0.120396 0.3048)
			(end 0.120396 0.2794)
			(stroke
				(width 0.1)
				(type default)
			)
			(layer "F.Fab")
		)
		(fp_line
			(start -0.12065 0.3048)
			(end -0.67945 0.3048)
			(stroke
				(width 0.1)
				(type default)
			)
			(layer "F.Fab")
		)
		(fp_line
			(start -0.67945 0.3048)
			(end -0.67945 -0.305054)
			(stroke
				(width 0.1)
				(type default)
			)
			(layer "F.Fab")
		)
		(pad "1" smd circle
			(at -0.40005 0 90)
			(size 0 0)
			(layers "F.Cu" "F.Mask" "F.Paste")
			(net "SMB_FIO_R2_SCL")
		)
		(pad "2" smd circle
			(at 0.40005 0 90)
			(size 0 0)
			(layers "F.Cu" "F.Mask" "F.Paste")
			(net "SMB_FIO_R1_SCL")
		)
	)
	(footprint ""
		(layer "F.Cu")
		(at 234.072938 -128.632966)
		(property "Reference" "J4"
			(at -1.156716 4.549902 0)
			(unlocked yes)
			(layer "F.SilkS")
			(effects
				(font
					(size 0.7874 0.5842)
					(thickness 0.1524)
				)
				(justify left)
			)
		)
		(property "Value" ""
			(at 0 0 0)
			(layer "F.Fab")
			(effects
				(font
					(size 1.27 1.27)
				)
			)
		)
		(duplicate_pad_numbers_are_jumpers no)
		(fp_line
			(start -1.27 -3.81)
			(end 1.27 -3.81)
			(stroke
				(width 0.1524)
				(type default)
			)
			(layer "F.SilkS")
		)
		(fp_line
			(start -1.27 -0.7747)
			(end -1.27 -3.81)
			(stroke
				(width 0.1524)
				(type default)
			)
			(layer "F.SilkS")
		)
		(fp_line
			(start -1.27 3.81)
			(end -1.27 0.7747)
			(stroke
				(width 0.1524)
				(type default)
			)
			(layer "F.SilkS")
		)
		(fp_line
			(start 1.27 -3.81)
			(end 1.27 -3.3147)
			(stroke
				(width 0.1524)
				(type default)
			)
			(layer "F.SilkS")
		)
		(fp_line
			(start 1.27 -1.7653)
			(end 1.27 1.7653)
			(stroke
				(width 0.1524)
				(type default)
			)
			(layer "F.SilkS")
		)
		(fp_line
			(start 1.27 3.3147)
			(end 1.27 3.81)
			(stroke
				(width 0.1524)
				(type default)
			)
			(layer "F.SilkS")
		)
		(fp_line
			(start 1.27 3.81)
			(end -1.27 3.81)
			(stroke
				(width 0.1524)
				(type default)
			)
			(layer "F.SilkS")
		)
		(fp_poly
			(pts
				(xy 4.3942 -3.048) (xy 4.3942 -2.032) (xy 3.3782 -2.54)
			)
			(stroke
				(width 0)
				(type default)
			)
			(fill yes)
			(layer "F.SilkS")
		)
		(fp_line
			(start -1.27 -3.81)
			(end -1.27 3.81)
			(stroke
				(width 0.1)
				(type default)
			)
			(layer "F.Fab")
		)
		(fp_line
			(start -1.27 3.81)
			(end 1.27 3.81)
			(stroke
				(width 0.1)
				(type default)
			)
			(layer "F.Fab")
		)
		(fp_line
			(start 1.27 -3.81)
			(end -1.27 -3.81)
			(stroke
				(width 0.1)
				(type default)
			)
			(layer "F.Fab")
		)
		(fp_line
			(start 1.27 3.81)
			(end 1.27 -3.81)
			(stroke
				(width 0.1)
				(type default)
			)
			(layer "F.Fab")
		)
		(fp_poly
			(pts
				(xy 4.3942 -3.048) (xy 4.3942 -2.032) (xy 3.3782 -2.54)
			)
			(stroke
				(width 0)
				(type default)
			)
			(fill yes)
			(layer "F.Fab")
		)
		(fp_text user "3"
			(at 3.921252 2.54 90)
			(unlocked yes)
			(layer "F.SilkS")
			(effects
				(font
					(size 0.7874 0.5842)
					(thickness 0.1524)
				)
			)
		)
		(fp_text user "3"
			(at 3.921252 2.54 90)
			(unlocked yes)
			(layer "F.Fab")
			(effects
				(font
					(size 0.7874 0.5842)
					(thickness 0.1524)
				)
			)
		)
		(pad "1" smd rect
			(at 1.459992 -2.54 90)
			(size 1.27 3.429)
			(layers "F.Cu" "F.Mask" "F.Paste")
			(net "Net_1738")
		)
		(pad "2" smd rect
			(at -1.459992 0 90)
			(size 1.27 3.429)
			(layers "F.Cu" "F.Mask" "F.Paste")
			(net "PEX_USB2_SEL")
		)
		(pad "3" smd rect
			(at 1.459992 2.54 90)
			(size 1.27 3.429)
			(layers "F.Cu" "F.Mask" "F.Paste")
			(net "PEX_USB2_SEL_CONN")
		)
	)
	(footprint ""
		(layer "F.Cu")
		(at 428.319438 -133.480302 180)
		(property "Reference" "C653"
			(at 0 0 180)
			(layer "F.SilkS")
			(hide yes)
			(effects
				(font
					(size 1.27 1.27)
				)
			)
		)
		(property "Value" ""
			(at 0 0 180)
			(layer "F.Fab")
			(effects
				(font
					(size 1.27 1.27)
				)
			)
		)
		(duplicate_pad_numbers_are_jumpers no)
		(fp_line
			(start 0.299974 0.150114)
			(end -0.299974 0.150114)
			(stroke
				(width 0.1)
				(type default)
			)
			(layer "F.Fab")
		)
		(fp_line
			(start 0.299974 -0.150114)
			(end 0.299974 0.150114)
			(stroke
				(width 0.1)
				(type default)
			)
			(layer "F.Fab")
		)
		(fp_line
			(start -0.299974 0.150114)
			(end -0.299974 -0.150114)
			(stroke
				(width 0.1)
				(type default)
			)
			(layer "F.Fab")
		)
		(fp_line
			(start -0.299974 -0.150114)
			(end 0.299974 -0.150114)
			(stroke
				(width 0.1)
				(type default)
			)
			(layer "F.Fab")
		)
		(pad "1" smd rect
			(at -0.2667 0 180)
			(size 0.3048 0.381)
			(layers "F.Cu" "F.Mask" "F.Paste")
			(net "P5E_PEX3_STN0_TX_DN<6>")
		)
		(pad "2" smd rect
			(at 0.2667 0 180)
			(size 0.3048 0.381)
			(layers "F.Cu" "F.Mask" "F.Paste")
			(net "P5E_PEX3_STN0_TX_C_DN<6>")
		)
	)
)
